(kicad_pcb
	(version 20260206)
	(generator "pcbnew")
	(generator_version "10.0")
	(general
		(thickness 1.6)
		(legacy_teardrops no)
	)
	(paper "A4")
	(title_block
		(title "04192023_DAF0TMB3IC0_F0TG_MB_C_brd_V02_OCP.brd")
		(comment 1 "Grand Teton / footprints 3635-3640 of 8354")
	)
	(layers
		(0 "F.Cu" signal "TOP")
		(4 "In1.Cu" signal "GND")
		(6 "In2.Cu" signal "IN1")
		(8 "In3.Cu" signal "GND1")
		(10 "In4.Cu" signal "IN2")
		(12 "In5.Cu" signal "GND2")
		(14 "In6.Cu" signal "IN3")
		(16 "In7.Cu" signal "GND3")
		(18 "In8.Cu" signal "VCC")
		(20 "In9.Cu" signal "VCC1")
		(22 "In10.Cu" signal "GND4")
		(24 "In11.Cu" signal "IN4")
		(26 "In12.Cu" signal "GND5")
		(28 "In13.Cu" signal "IN5")
		(30 "In14.Cu" signal "GND6")
		(32 "In15.Cu" signal "IN6")
		(34 "In16.Cu" signal "GND7")
		(2 "B.Cu" signal "BOTTOM")
		(9 "F.Adhes" user "F.Adhesive")
		(11 "B.Adhes" user "B.Adhesive")
		(13 "F.Paste" user "Package Geometry/Pastemask Top")
		(15 "B.Paste" user "Package Geometry/Pastemask Bottom")
		(5 "F.SilkS" user "Ref Des/Silkscreen Top")
		(7 "B.SilkS" user "Ref Des/Silkscreen Bottom")
		(1 "F.Mask" user "Board Geometry/Soldermask Top")
		(3 "B.Mask" user "Board Geometry/Soldermask Bottom")
		(17 "Dwgs.User" user "User.Drawings")
		(19 "Cmts.User" user "User.Comments")
		(21 "Eco1.User" user "User.Eco1")
		(23 "Eco2.User" user "User.Eco2")
		(25 "Edge.Cuts" user "Board Geometry/Outline")
		(27 "Margin" user)
		(31 "F.CrtYd" user "Package Geometry/Place Bound Top")
		(29 "B.CrtYd" user "Package Geometry/Place Bound Bottom")
		(35 "F.Fab" user "Ref Des/Assembly Top")
		(33 "B.Fab" user "Ref Des/Assembly Bottom")
	)
	(footprint ""
		(layer "F.Cu")
		(at 282.575 -423.418 -90)
		(property "Reference" "R4491"
			(at 0 0 270)
			(layer "F.SilkS")
			(hide yes)
			(effects
				(font
					(size 1.27 1.27)
				)
			)
		)
		(property "Value" ""
			(at 0 0 270)
			(layer "F.Fab")
			(effects
				(font
					(size 1.27 1.27)
				)
			)
		)
		(duplicate_pad_numbers_are_jumpers no)
		(fp_line
			(start -0.7874 0.4064)
			(end -0.7874 -0.4064)
			(stroke
				(width 0.1524)
				(type default)
			)
			(layer "F.SilkS")
		)
		(fp_line
			(start 0.7874 0.4064)
			(end -0.7874 0.4064)
			(stroke
				(width 0.1524)
				(type default)
			)
			(layer "F.SilkS")
		)
		(fp_line
			(start -0.7874 -0.4064)
			(end 0.7874 -0.4064)
			(stroke
				(width 0.1524)
				(type default)
			)
			(layer "F.SilkS")
		)
		(fp_line
			(start 0.7874 -0.4064)
			(end 0.7874 0.4064)
			(stroke
				(width 0.1524)
				(type default)
			)
			(layer "F.SilkS")
		)
		(fp_line
			(start -0.67945 0.3048)
			(end -0.67945 -0.305054)
			(stroke
				(width 0.1)
				(type default)
			)
			(layer "F.Fab")
		)
		(fp_line
			(start -0.12065 0.3048)
			(end -0.67945 0.3048)
			(stroke
				(width 0.1)
				(type default)
			)
			(layer "F.Fab")
		)
		(fp_line
			(start 0.120396 0.3048)
			(end 0.120396 0.2794)
			(stroke
				(width 0.1)
				(type default)
			)
			(layer "F.Fab")
		)
		(fp_line
			(start 0.67945 0.3048)
			(end 0.120396 0.3048)
			(stroke
				(width 0.1)
				(type default)
			)
			(layer "F.Fab")
		)
		(fp_line
			(start -0.12065 0.2794)
			(end -0.12065 0.3048)
			(stroke
				(width 0.1)
				(type default)
			)
			(layer "F.Fab")
		)
		(fp_line
			(start 0.120396 0.2794)
			(end -0.12065 0.2794)
			(stroke
				(width 0.1)
				(type default)
			)
			(layer "F.Fab")
		)
		(fp_line
			(start -0.12065 -0.2794)
			(end 0.12065 -0.2794)
			(stroke
				(width 0.1)
				(type default)
			)
			(layer "F.Fab")
		)
		(fp_line
			(start 0.12065 -0.2794)
			(end 0.12065 -0.3048)
			(stroke
				(width 0.1)
				(type default)
			)
			(layer "F.Fab")
		)
		(fp_line
			(start 0.12065 -0.3048)
			(end 0.67945 -0.3048)
			(stroke
				(width 0.1)
				(type default)
			)
			(layer "F.Fab")
		)
		(fp_line
			(start 0.67945 -0.3048)
			(end 0.67945 0.3048)
			(stroke
				(width 0.1)
				(type default)
			)
			(layer "F.Fab")
		)
		(fp_line
			(start -0.67945 -0.305054)
			(end -0.12065 -0.305054)
			(stroke
				(width 0.1)
				(type default)
			)
			(layer "F.Fab")
		)
		(fp_line
			(start -0.12065 -0.305054)
			(end -0.12065 -0.2794)
			(stroke
				(width 0.1)
				(type default)
			)
			(layer "F.Fab")
		)
		(pad "1" smd circle
			(at -0.40005 0 270)
			(size 0 0)
			(layers "F.Cu" "F.Mask" "F.Paste")
			(net "P3V3_AUX")
		)
		(pad "2" smd circle
			(at 0.40005 0 270)
			(size 0 0)
			(layers "F.Cu" "F.Mask" "F.Paste")
			(net "CLK_9ZXL045_P0_HIBW")
		)
	)
	(footprint ""
		(layer "F.Cu")
		(at 59.508644 -180.746908)
		(property "Reference" "PR162"
			(at 0 0 0)
			(layer "F.SilkS")
			(hide yes)
			(effects
				(font
					(size 1.27 1.27)
				)
			)
		)
		(property "Value" ""
			(at 0 0 0)
			(layer "F.Fab")
			(effects
				(font
					(size 1.27 1.27)
				)
			)
		)
		(duplicate_pad_numbers_are_jumpers no)
		(fp_line
			(start -0.7874 -0.4064)
			(end 0.7874 -0.4064)
			(stroke
				(width 0.1524)
				(type default)
			)
			(layer "F.SilkS")
		)
		(fp_line
			(start -0.7874 0.4064)
			(end -0.7874 -0.4064)
			(stroke
				(width 0.1524)
				(type default)
			)
			(layer "F.SilkS")
		)
		(fp_line
			(start 0.7874 -0.4064)
			(end 0.7874 0.4064)
			(stroke
				(width 0.1524)
				(type default)
			)
			(layer "F.SilkS")
		)
		(fp_line
			(start 0.7874 0.4064)
			(end -0.7874 0.4064)
			(stroke
				(width 0.1524)
				(type default)
			)
			(layer "F.SilkS")
		)
		(fp_line
			(start -0.67945 -0.305054)
			(end -0.12065 -0.305054)
			(stroke
				(width 0.1)
				(type default)
			)
			(layer "F.Fab")
		)
		(fp_line
			(start -0.67945 0.3048)
			(end -0.67945 -0.305054)
			(stroke
				(width 0.1)
				(type default)
			)
			(layer "F.Fab")
		)
		(fp_line
			(start -0.12065 -0.305054)
			(end -0.12065 -0.2794)
			(stroke
				(width 0.1)
				(type default)
			)
			(layer "F.Fab")
		)
		(fp_line
			(start -0.12065 -0.2794)
			(end 0.12065 -0.2794)
			(stroke
				(width 0.1)
				(type default)
			)
			(layer "F.Fab")
		)
		(fp_line
			(start -0.12065 0.2794)
			(end -0.12065 0.3048)
			(stroke
				(width 0.1)
				(type default)
			)
			(layer "F.Fab")
		)
		(fp_line
			(start -0.12065 0.3048)
			(end -0.67945 0.3048)
			(stroke
				(width 0.1)
				(type default)
			)
			(layer "F.Fab")
		)
		(fp_line
			(start 0.120396 0.2794)
			(end -0.12065 0.2794)
			(stroke
				(width 0.1)
				(type default)
			)
			(layer "F.Fab")
		)
		(fp_line
			(start 0.120396 0.3048)
			(end 0.120396 0.2794)
			(stroke
				(width 0.1)
				(type default)
			)
			(layer "F.Fab")
		)
		(fp_line
			(start 0.12065 -0.3048)
			(end 0.67945 -0.3048)
			(stroke
				(width 0.1)
				(type default)
			)
			(layer "F.Fab")
		)
		(fp_line
			(start 0.12065 -0.2794)
			(end 0.12065 -0.3048)
			(stroke
				(width 0.1)
				(type default)
			)
			(layer "F.Fab")
		)
		(fp_line
			(start 0.67945 -0.3048)
			(end 0.67945 0.3048)
			(stroke
				(width 0.1)
				(type default)
			)
			(layer "F.Fab")
		)
		(fp_line
			(start 0.67945 0.3048)
			(end 0.120396 0.3048)
			(stroke
				(width 0.1)
				(type default)
			)
			(layer "F.Fab")
		)
		(pad "1" smd circle
			(at -0.40005 0)
			(size 0 0)
			(layers "F.Cu" "F.Mask" "F.Paste")
			(net "VSENSE_VSS_SENSE_A_P1")
		)
		(pad "2" smd circle
			(at 0.40005 0)
			(size 0 0)
			(layers "F.Cu" "F.Mask" "F.Paste")
			(net "GND")
		)
	)
	(footprint ""
		(layer "F.Cu")
		(at 360.583988 -409.388818 -90)
		(property "Reference" "R4515"
			(at 0 0 270)
			(layer "F.SilkS")
			(hide yes)
			(effects
				(font
					(size 1.27 1.27)
				)
			)
		)
		(property "Value" ""
			(at 0 0 270)
			(layer "F.Fab")
			(effects
				(font
					(size 1.27 1.27)
				)
			)
		)
		(duplicate_pad_numbers_are_jumpers no)
		(fp_line
			(start -0.7874 0.4064)
			(end -0.7874 -0.4064)
			(stroke
				(width 0.1524)
				(type default)
			)
			(layer "F.SilkS")
		)
		(fp_line
			(start 0.7874 0.4064)
			(end -0.7874 0.4064)
			(stroke
				(width 0.1524)
				(type default)
			)
			(layer "F.SilkS")
		)
		(fp_line
			(start -0.7874 -0.4064)
			(end 0.7874 -0.4064)
			(stroke
				(width 0.1524)
				(type default)
			)
			(layer "F.SilkS")
		)
		(fp_line
			(start 0.7874 -0.4064)
			(end 0.7874 0.4064)
			(stroke
				(width 0.1524)
				(type default)
			)
			(layer "F.SilkS")
		)
		(fp_line
			(start -0.67945 0.3048)
			(end -0.67945 -0.305054)
			(stroke
				(width 0.1)
				(type default)
			)
			(layer "F.Fab")
		)
		(fp_line
			(start -0.12065 0.3048)
			(end -0.67945 0.3048)
			(stroke
				(width 0.1)
				(type default)
			)
			(layer "F.Fab")
		)
		(fp_line
			(start 0.120396 0.3048)
			(end 0.120396 0.2794)
			(stroke
				(width 0.1)
				(type default)
			)
			(layer "F.Fab")
		)
		(fp_line
			(start 0.67945 0.3048)
			(end 0.120396 0.3048)
			(stroke
				(width 0.1)
				(type default)
			)
			(layer "F.Fab")
		)
		(fp_line
			(start -0.12065 0.2794)
			(end -0.12065 0.3048)
			(stroke
				(width 0.1)
				(type default)
			)
			(layer "F.Fab")
		)
		(fp_line
			(start 0.120396 0.2794)
			(end -0.12065 0.2794)
			(stroke
				(width 0.1)
				(type default)
			)
			(layer "F.Fab")
		)
		(fp_line
			(start -0.12065 -0.2794)
			(end 0.12065 -0.2794)
			(stroke
				(width 0.1)
				(type default)
			)
			(layer "F.Fab")
		)
		(fp_line
			(start 0.12065 -0.2794)
			(end 0.12065 -0.3048)
			(stroke
				(width 0.1)
				(type default)
			)
			(layer "F.Fab")
		)
		(fp_line
			(start 0.12065 -0.3048)
			(end 0.67945 -0.3048)
			(stroke
				(width 0.1)
				(type default)
			)
			(layer "F.Fab")
		)
		(fp_line
			(start 0.67945 -0.3048)
			(end 0.67945 0.3048)
			(stroke
				(width 0.1)
				(type default)
			)
			(layer "F.Fab")
		)
		(fp_line
			(start -0.67945 -0.305054)
			(end -0.12065 -0.305054)
			(stroke
				(width 0.1)
				(type default)
			)
			(layer "F.Fab")
		)
		(fp_line
			(start -0.12065 -0.305054)
			(end -0.12065 -0.2794)
			(stroke
				(width 0.1)
				(type default)
			)
			(layer "F.Fab")
		)
		(pad "1" smd circle
			(at -0.40005 0 270)
			(size 0 0)
			(layers "F.Cu" "F.Mask" "F.Paste")
			(net "P3V3_AUX")
		)
		(pad "2" smd circle
			(at 0.40005 0 270)
			(size 0 0)
			(layers "F.Cu" "F.Mask" "F.Paste")
			(net "UART_BMC_BIC_RX")
		)
	)
	(footprint ""
		(layer "F.Cu")
		(at 82.306668 -17.745202)
		(property "Reference" "R3831"
			(at 0 0 0)
			(layer "F.SilkS")
			(hide yes)
			(effects
				(font
					(size 1.27 1.27)
				)
			)
		)
		(property "Value" ""
			(at 0 0 0)
			(layer "F.Fab")
			(effects
				(font
					(size 1.27 1.27)
				)
			)
		)
		(duplicate_pad_numbers_are_jumpers no)
		(fp_line
			(start -0.7874 -0.4064)
			(end 0.7874 -0.4064)
			(stroke
				(width 0.1524)
				(type default)
			)
			(layer "F.SilkS")
		)
		(fp_line
			(start -0.7874 0.4064)
			(end -0.7874 -0.4064)
			(stroke
				(width 0.1524)
				(type default)
			)
			(layer "F.SilkS")
		)
		(fp_line
			(start 0.7874 -0.4064)
			(end 0.7874 0.4064)
			(stroke
				(width 0.1524)
				(type default)
			)
			(layer "F.SilkS")
		)
		(fp_line
			(start 0.7874 0.4064)
			(end -0.7874 0.4064)
			(stroke
				(width 0.1524)
				(type default)
			)
			(layer "F.SilkS")
		)
		(fp_line
			(start -0.67945 -0.305054)
			(end -0.12065 -0.305054)
			(stroke
				(width 0.1)
				(type default)
			)
			(layer "F.Fab")
		)
		(fp_line
			(start -0.67945 0.3048)
			(end -0.67945 -0.305054)
			(stroke
				(width 0.1)
				(type default)
			)
			(layer "F.Fab")
		)
		(fp_line
			(start -0.12065 -0.305054)
			(end -0.12065 -0.2794)
			(stroke
				(width 0.1)
				(type default)
			)
			(layer "F.Fab")
		)
		(fp_line
			(start -0.12065 -0.2794)
			(end 0.12065 -0.2794)
			(stroke
				(width 0.1)
				(type default)
			)
			(layer "F.Fab")
		)
		(fp_line
			(start -0.12065 0.2794)
			(end -0.12065 0.3048)
			(stroke
				(width 0.1)
				(type default)
			)
			(layer "F.Fab")
		)
		(fp_line
			(start -0.12065 0.3048)
			(end -0.67945 0.3048)
			(stroke
				(width 0.1)
				(type default)
			)
			(layer "F.Fab")
		)
		(fp_line
			(start 0.120396 0.2794)
			(end -0.12065 0.2794)
			(stroke
				(width 0.1)
				(type default)
			)
			(layer "F.Fab")
		)
		(fp_line
			(start 0.120396 0.3048)
			(end 0.120396 0.2794)
			(stroke
				(width 0.1)
				(type default)
			)
			(layer "F.Fab")
		)
		(fp_line
			(start 0.12065 -0.3048)
			(end 0.67945 -0.3048)
			(stroke
				(width 0.1)
				(type default)
			)
			(layer "F.Fab")
		)
		(fp_line
			(start 0.12065 -0.2794)
			(end 0.12065 -0.3048)
			(stroke
				(width 0.1)
				(type default)
			)
			(layer "F.Fab")
		)
		(fp_line
			(start 0.67945 -0.3048)
			(end 0.67945 0.3048)
			(stroke
				(width 0.1)
				(type default)
			)
			(layer "F.Fab")
		)
		(fp_line
			(start 0.67945 0.3048)
			(end 0.120396 0.3048)
			(stroke
				(width 0.1)
				(type default)
			)
			(layer "F.Fab")
		)
		(pad "1" smd circle
			(at -0.40005 0)
			(size 0 0)
			(layers "F.Cu" "F.Mask" "F.Paste")
			(net "P12V_OCP_PWRGD_2")
		)
		(pad "2" smd circle
			(at 0.40005 0)
			(size 0 0)
			(layers "F.Cu" "F.Mask" "F.Paste")
			(net "HP_LVC3_OCP_V3_2_P12V_PWRGD")
		)
	)
	(footprint ""
		(layer "F.Cu")
		(at 185.26252 -19.435572 90)
		(property "Reference" "R6065"
			(at 0 0 90)
			(layer "F.SilkS")
			(hide yes)
			(effects
				(font
					(size 1.27 1.27)
				)
			)
		)
		(property "Value" ""
			(at 0 0 90)
			(layer "F.Fab")
			(effects
				(font
					(size 1.27 1.27)
				)
			)
		)
		(duplicate_pad_numbers_are_jumpers no)
		(fp_line
			(start 0.7874 -0.4064)
			(end 0.7874 0.4064)
			(stroke
				(width 0.1524)
				(type default)
			)
			(layer "F.SilkS")
		)
		(fp_line
			(start -0.7874 -0.4064)
			(end 0.7874 -0.4064)
			(stroke
				(width 0.1524)
				(type default)
			)
			(layer "F.SilkS")
		)
		(fp_line
			(start 0.7874 0.4064)
			(end -0.7874 0.4064)
			(stroke
				(width 0.1524)
				(type default)
			)
			(layer "F.SilkS")
		)
		(fp_line
			(start -0.7874 0.4064)
			(end -0.7874 -0.4064)
			(stroke
				(width 0.1524)
				(type default)
			)
			(layer "F.SilkS")
		)
		(fp_line
			(start -0.12065 -0.305054)
			(end -0.12065 -0.2794)
			(stroke
				(width 0.1)
				(type default)
			)
			(layer "F.Fab")
		)
		(fp_line
			(start -0.67945 -0.305054)
			(end -0.12065 -0.305054)
			(stroke
				(width 0.1)
				(type default)
			)
			(layer "F.Fab")
		)
		(fp_line
			(start 0.67945 -0.3048)
			(end 0.67945 0.3048)
			(stroke
				(width 0.1)
				(type default)
			)
			(layer "F.Fab")
		)
		(fp_line
			(start 0.12065 -0.3048)
			(end 0.67945 -0.3048)
			(stroke
				(width 0.1)
				(type default)
			)
			(layer "F.Fab")
		)
		(fp_line
			(start 0.12065 -0.2794)
			(end 0.12065 -0.3048)
			(stroke
				(width 0.1)
				(type default)
			)
			(layer "F.Fab")
		)
		(fp_line
			(start -0.12065 -0.2794)
			(end 0.12065 -0.2794)
			(stroke
				(width 0.1)
				(type default)
			)
			(layer "F.Fab")
		)
		(fp_line
			(start 0.120396 0.2794)
			(end -0.12065 0.2794)
			(stroke
				(width 0.1)
				(type default)
			)
			(layer "F.Fab")
		)
		(fp_line
			(start -0.12065 0.2794)
			(end -0.12065 0.3048)
			(stroke
				(width 0.1)
				(type default)
			)
			(layer "F.Fab")
		)
		(fp_line
			(start 0.67945 0.3048)
			(end 0.120396 0.3048)
			(stroke
				(width 0.1)
				(type default)
			)
			(layer "F.Fab")
		)
		(fp_line
			(start 0.120396 0.3048)
			(end 0.120396 0.2794)
			(stroke
				(width 0.1)
				(type default)
			)
			(layer "F.Fab")
		)
		(fp_line
			(start -0.12065 0.3048)
			(end -0.67945 0.3048)
			(stroke
				(width 0.1)
				(type default)
			)
			(layer "F.Fab")
		)
		(fp_line
			(start -0.67945 0.3048)
			(end -0.67945 -0.305054)
			(stroke
				(width 0.1)
				(type default)
			)
			(layer "F.Fab")
		)
		(pad "1" smd circle
			(at -0.40005 0 90)
			(size 0 0)
			(layers "F.Cu" "F.Mask" "F.Paste")
			(net "UART_CPU0_SCM_LVC3_UART1_R1_TX")
		)
		(pad "2" smd circle
			(at 0.40005 0 90)
			(size 0 0)
			(layers "F.Cu" "F.Mask" "F.Paste")
			(net "UART_CPU0_SCM_LVC3_UART1_TX")
		)
	)
	(footprint ""
		(layer "F.Cu")
		(at 54.96433 -16.099536 90)
		(property "Reference" "C706"
			(at 0 0 90)
			(layer "F.SilkS")
			(hide yes)
			(effects
				(font
					(size 1.27 1.27)
				)
			)
		)
		(property "Value" ""
			(at 0 0 90)
			(layer "F.Fab")
			(effects
				(font
					(size 1.27 1.27)
				)
			)
		)
		(duplicate_pad_numbers_are_jumpers no)
		(fp_line
			(start 0.299974 -0.150114)
			(end 0.299974 0.150114)
			(stroke
				(width 0.1)
				(type default)
			)
			(layer "F.Fab")
		)
		(fp_line
			(start -0.299974 -0.150114)
			(end 0.299974 -0.150114)
			(stroke
				(width 0.1)
				(type default)
			)
			(layer "F.Fab")
		)
		(fp_line
			(start 0.299974 0.150114)
			(end -0.299974 0.150114)
			(stroke
				(width 0.1)
				(type default)
			)
			(layer "F.Fab")
		)
		(fp_line
			(start -0.299974 0.150114)
			(end -0.299974 -0.150114)
			(stroke
				(width 0.1)
				(type default)
			)
			(layer "F.Fab")
		)
		(pad "1" smd rect
			(at -0.2667 0 90)
			(size 0.3048 0.381)
			(layers "F.Cu" "F.Mask" "F.Paste")
			(net "P5E_CPU1_G1_TX_C_DN<1>")
		)
		(pad "2" smd rect
			(at 0.2667 0 90)
			(size 0.3048 0.381)
			(layers "F.Cu" "F.Mask" "F.Paste")
			(net "P5E_CPU1_G1_TX_DN<1>")
		)
	)
)
